# S9S_MB_2U (Grand Teton) — schematic parts with pin connectivity, parts 5880–5880 of 6093; source: Cadence DE-HDL packaged netlist (pstxprt.dat, pstxnet.dat, pstchip.dat)

U2  SOCKET4677_AZIF0045P001C01CS  SOCKET4677_AZIF0045-P001C01CS IO  pkg SOCKET4677_82X64-5XA_H466  page 13  (pins 4239-4564 of 4677)
  L21  VSS1651  POWER  = GND
  L23  VSS1655  POWER  = GND
  L25  VSS1656  POWER  = GND
  L27  VSS1658  POWER  = GND
  L29  VSS1659  POWER  = GND
  L31  VSS1660  POWER  = GND
  L33  VSS1661  POWER  = GND
  L35  VSS1662  POWER  = GND
  L37  VSS1663  POWER  = GND
  L39  VSS1665  POWER  = GND
  L41  VSS1666  POWER  = GND
  L43  VSS1667  POWER  = GND
  L45  VSS1668  POWER  = GND
  L48  VSS1670  POWER  = GND
  L50  VSS1672  POWER  = GND
  L52  VSS1673  POWER  = GND
  L54  VSS1674  POWER  = GND
  L56  VSS1676  POWER  = GND
  L58  VSS1634  POWER  = GND
  L60  VSS1677  POWER  = GND
  L62  VSS1678  POWER  = GND
  L64  VSS1679  POWER  = GND
  L66  VSS1680  POWER  = GND
  L68  VSS1681  POWER  = GND
  L70  VSS1640  POWER  = GND
  L72  VSS1682  POWER  = GND
  L74  VSS1683  POWER  = GND
  L76  VSS1684  POWER  = GND
  L78  VSS1685  POWER  = GND
  L80  UPI2_RX_DN5  IN  = UPI_CPU1_CPU0_P2P2_DN<18>
  L82  UPI2_RX_DP4  IN  = UPI_CPU1_CPU0_P2P2_DP<19>
  L84  VCCFA_EHV_FIVRA89  POWER  = PVCCFA_EHV_FIVRA_CPU0
  L86  PE4_TX_DN0  OUT  = P5E_CPU0_PE4_TX_DN<0>
  L88  VSS1646  POWER  = GND
  L90  VSS1648  POWER  = GND
  M2  UPI0_TX_DN1  OUT  = UPI_CPU0_CPU1_P0P1_DN<1>
  M4  VSS1652  POWER  = GND
  M6  UPI0_RX_DP1  IN  = UPI_CPU1_CPU0_P1P0_DP<1>
  M8  VSS1657  POWER  = GND
  M10  PE0_RX_DN1  IN  = P5E_CPU0_PE0_RX_DN<1>
  M12  VSS1649  POWER  = GND
  M14  PE0_TX_DP0  OUT  = P5E_CPU0_PE0_TX_DP<0>
  M16  DDR1_SB_DQ23  BI  = M_B_CPU0_SB_DQ<23>
  M18  DDR1_SB_DQS_DN7  BI  = M_B_CPU0_SB_DQS_DN<7>
  M20  DDR1_SB_DQ18  BI  = M_B_CPU0_SB_DQ<18>
  M22  DDR1_SB_DQ15  BI  = M_B_CPU0_SB_DQ<15>
  M24  DDR1_SB_DQS_DN6  BI  = M_B_CPU0_SB_DQS_DN<6>
  M26  DDR1_SB_DQ10  BI  = M_B_CPU0_SB_DQ<10>
  M28  DDR0_SB_DQ7  BI  = M_A_CPU0_SB_DQ<7>
  M30  DDR0_SB_DQS_DN5  BI  = M_A_CPU0_SB_DQS_DN<5>
  M32  DDR0_SB_DQ2  BI  = M_A_CPU0_SB_DQ<2>
  M34  DDR1_SB_ECC3  BI  = M_B_CPU0_SB_CB<3>
  M36  DDR1_SB_DQS_DP4  BI  = M_B_CPU0_SB_DQS_DP<4>
  M38  DDR1_SB_ECC6  BI  = M_B_CPU0_SB_CB<6>
  M40  DDR1_SB_CS_N3  OUT  = M_B_CPU0_SB_CS_N<3>
  M42  VSS1653  POWER  = GND
  M44  DDR1_SB_CA3  OUT  = M_B_CPU0_SB_CA<3>
  M47  DDR1_SA_CA5  OUT  = M_B_CPU0_SA_CA<5>
  M49  VSS1654  POWER  = GND
  M51  DDR1_SA_CS_N2  OUT  = M_B_CPU0_SA_CS_N<2>
  M53  DDR1_SA_ECC7  BI  = M_B_CPU0_SA_CB<7>
  M55  DDR1_SA_DQS_DN9  BI  = M_B_CPU0_SA_DQS_DN<9>
  M57  DDR1_SA_ECC2  BI  = M_B_CPU0_SA_CB<2>
  M59  DDR1_SA_DQ23  BI  = M_B_CPU0_SA_DQ<23>
  M61  DDR1_SA_DQS_DN7  BI  = M_B_CPU0_SA_DQS_DN<7>
  M63  DDR1_SA_DQ18  BI  = M_B_CPU0_SA_DQ<18>
  M65  DDR0_SA_DQ15  BI  = M_A_CPU0_SA_DQ<15>
  M67  DDR0_SA_DQS_DP6  BI  = M_A_CPU0_SA_DQS_DP<6>
  M69  DDR0_SA_DQ10  BI  = M_A_CPU0_SA_DQ<10>
  M71  DDR1_SA_DQ7  BI  = M_B_CPU0_SA_DQ<7>
  M73  DDR1_SA_DQS_DN5  BI  = M_B_CPU0_SA_DQS_DN<5>
  M75  DDR1_SA_DQ2  BI  = M_B_CPU0_SA_DQ<2>
  M77  DDR0_SA_DQ2  BI  = M_A_CPU0_SA_DQ<2>
  M79  UPI2_RX_DP3  IN  = UPI_CPU1_CPU0_P2P2_DP<20>
  M81  VSS1686  POWER  = GND
  M83  VSS1687  POWER  = GND
  M85  VCCFA_EHV_FIVRA90  POWER  = PVCCFA_EHV_FIVRA_CPU0
  M87  PE4_TX_DP0  OUT  = P5E_CPU0_PE4_TX_DP<0>
  M89  VCCFA_EHV_FIVRA91  POWER  = PVCCFA_EHV_FIVRA_CPU0
  N1  UPI0_TX_DN2  OUT  = UPI_CPU0_CPU1_P0P1_DN<2>
  N3  VCCFA_EHV8  POWER  = PVCCFA_EHV_CPU0
  N5  UPI0_RX_DN1  IN  = UPI_CPU1_CPU0_P1P0_DN<1>
  N7  VCCFA_EHV_FIVRA93  POWER  = PVCCFA_EHV_FIVRA_CPU0
  N9  PE0_RX_DP1  IN  = P5E_CPU0_PE0_RX_DP<1>
  N11  VCCFA_EHV_FIVRA92  POWER  = PVCCFA_EHV_FIVRA_CPU0
  N13  PE0_TX_DN0  OUT  = P5E_CPU0_PE0_TX_DN<0>
  N15  VSS1688  POWER  = GND
  N17  DDR1_SB_DQ22  BI  = M_B_CPU0_SB_DQ<22>
  N19  DDR1_SB_DQ19  BI  = M_B_CPU0_SB_DQ<19>
  N21  VSS1664  POWER  = GND
  N23  DDR1_SB_DQ14  BI  = M_B_CPU0_SB_DQ<14>
  N25  DDR1_SB_DQ11  BI  = M_B_CPU0_SB_DQ<11>
  N27  VSS1689  POWER  = GND
  N29  DDR0_SB_DQ6  BI  = M_A_CPU0_SB_DQ<6>
  N31  DDR0_SB_DQ3  BI  = M_A_CPU0_SB_DQ<3>
  N33  VSS1691  POWER  = GND
  N35  DDR1_SB_ECC2  BI  = M_B_CPU0_SB_CB<2>
  N37  DDR1_SB_ECC7  BI  = M_B_CPU0_SB_CB<7>
  N39  VSS1669  POWER  = GND
  N41  DDR1_SB_CS_N2  OUT  = M_B_CPU0_SB_CS_N<2>
  N43  DDR1_SB_CA5  OUT  = M_B_CPU0_SB_CA<5>
  N45  VSS1692  POWER  = GND
  N48  DDR1_SA_CA3  OUT  = M_B_CPU0_SA_CA<3>
  N50  DDR1_SA_CS_N3  OUT  = M_B_CPU0_SA_CS_N<3>
  N52  VSS1693  POWER  = GND
  N54  DDR1_SA_ECC6  BI  = M_B_CPU0_SA_CB<6>
  N56  DDR1_SA_ECC3  BI  = M_B_CPU0_SA_CB<3>
  N58  VSS1694  POWER  = GND
  N60  DDR1_SA_DQ22  BI  = M_B_CPU0_SA_DQ<22>
  N62  DDR1_SA_DQ19  BI  = M_B_CPU0_SA_DQ<19>
  N64  VSS1675  POWER  = GND
  N66  DDR0_SA_DQ14  BI  = M_A_CPU0_SA_DQ<14>
  N68  DDR0_SA_DQ11  BI  = M_A_CPU0_SA_DQ<11>
  N70  VSS1695  POWER  = GND
  N72  DDR1_SA_DQ6  BI  = M_B_CPU0_SA_DQ<6>
  N74  DDR1_SA_DQ3  BI  = M_B_CPU0_SA_DQ<3>
  N76  VSS1696  POWER  = GND
  N78  VSS1698  POWER  = GND
  N80  VSS1700  POWER  = GND
  N82  VSS1701  POWER  = GND
  N84  VSS1702  POWER  = GND
  N86  PE4_TX_DP1  OUT  = P5E_CPU0_PE4_TX_DP<1>
  N88  VSS1703  POWER  = GND
  N90  PE4_RX_DP1  IN  = P5E_CPU0_PE4_RX_DP<1>
  P2  UPI0_TX_DP2  OUT  = UPI_CPU0_CPU1_P0P1_DP<2>
  P4  VSS1716  POWER  = GND
  P6  UPI0_RX_DN2  IN  = UPI_CPU1_CPU0_P1P0_DN<2>
  P8  VSS1729  POWER  = GND
  P10  PE0_RX_DN2  IN  = P5E_CPU0_PE0_RX_DN<2>
  P12  VSS1705  POWER  = GND
  P14  PE0_TX_DN1  OUT  = P5E_CPU0_PE0_TX_DN<1>
  P16  VSS1706  POWER  = GND
  P18  DDR1_SB_DQS_DP7  BI  = M_B_CPU0_SB_DQS_DP<7>
  P20  VSS1707  POWER  = GND
  P22  VSS1708  POWER  = GND
  P24  DDR1_SB_DQS_DP6  BI  = M_B_CPU0_SB_DQS_DP<6>
  P26  VSS1709  POWER  = GND
  P28  VSS1710  POWER  = GND
  P30  DDR0_SB_DQS_DP5  BI  = M_A_CPU0_SB_DQS_DP<5>
  P32  VSS1690  POWER  = GND
  P34  VSS1712  POWER  = GND
  P36  DDR1_SB_DQS_DN4  BI  = M_B_CPU0_SB_DQS_DN<4>
  P38  VSS1713  POWER  = GND
  P40  VSS1717  POWER  = GND
  P42  DDR1_SB_PAR  OUT  = M_B_CPU0_SB_PAR
  P44  VSS1718  POWER  = GND
  P47  VSS1719  POWER  = GND
  P49  DDR1_SA_CA1  OUT  = M_B_CPU0_SA_CA<1>
  P51  VSS1697  POWER  = GND
  P53  VSS1720  POWER  = GND
  P55  DDR1_SA_DQS_DP9  BI  = M_B_CPU0_SA_DQS_DP<9>
  P57  VSS1699  POWER  = GND
  P59  VSS1721  POWER  = GND
  P61  DDR1_SA_DQS_DP7  BI  = M_B_CPU0_SA_DQS_DP<7>
  P63  VSS1722  POWER  = GND
  P65  VSS1724  POWER  = GND
  P67  DDR0_SA_DQS_DN6  BI  = M_A_CPU0_SA_DQS_DN<6>
  P69  VSS1725  POWER  = GND
  P71  VSS1704  POWER  = GND
  P73  DDR1_SA_DQS_DP5  BI  = M_B_CPU0_SA_DQS_DP<5>
  P75  VSS1726  POWER  = GND
  P77  VSS1727  POWER  = GND
  P79  VCCFA_EHV_FIVRA94  POWER  = PVCCFA_EHV_FIVRA_CPU0
  P81  UPI2_TX_DN5  OUT  = UPI_CPU0_CPU1_P2P2_DN<18>
  P83  UPI2_TX_DP6  OUT  = UPI_CPU0_CPU1_P2P2_DP<17>
  P85  PE4_TX_DN1  OUT  = P5E_CPU0_PE4_TX_DN<1>
  P87  VSS1731  POWER  = GND
  P89  PE4_RX_DN1  IN  = P5E_CPU0_PE4_RX_DN<1>
  P91  VSS1732  POWER  = GND
  R1  VSS1711  POWER  = GND
  R3  UPI0_TX_DP3  OUT  = UPI_CPU0_CPU1_P0P1_DP<3>
  R5  VSS1745  POWER  = GND
  R7  UPI0_RX_DP2  IN  = UPI_CPU1_CPU0_P1P0_DP<2>
  R9  VSS1759  POWER  = GND
  R11  PE0_RX_DP2  IN  = P5E_CPU0_PE0_RX_DP<2>
  R13  VSS1733  POWER  = GND
  R15  PE0_TX_DP1  OUT  = P5E_CPU0_PE0_TX_DP<1>
  R17  VSS1734  POWER  = GND
  R19  VSS1714  POWER  = GND
  R21  DDR2_SB_DQS_DN2  BI  = M_C_CPU0_SB_DQS_DN<2>
  R23  VSS1715  POWER  = GND
  R25  VSS1735  POWER  = GND
  R27  DDR1_SB_DQS_DN0  BI  = M_B_CPU0_SB_DQS_DN<0>
  R29  VSS1736  POWER  = GND
  R31  VSS1737  POWER  = GND
  R33  DDR2_SB_DQS_DN9  BI  = M_C_CPU0_SB_DQS_DN<9>
  R35  VSS1738  POWER  = GND
  R37  VSS1742  POWER  = GND
  R39  DDR2_SB_CA6  OUT  = M_C_CPU0_SB_CA<6>
  R41  VSS1743  POWER  = GND
  R43  VSS1744  POWER  = GND
  R45  DDR1_CLK_DN0  OUT  = M_B_CPU0_CLK_DN<0>
  R48  VSS1723  POWER  = GND
  R50  VSS1747  POWER  = GND
  R52  DDR2_SA_CA0  OUT  = M_C_CPU0_SA_CA<0>
  R54  VSS1748  POWER  = GND
  R56  VSS1751  POWER  = GND
  R58  DDR1_SA_DQS_DN3  BI  = M_B_CPU0_SA_DQS_DN<3>
  R60  VSS1728  POWER  = GND
  R62  VSS1752  POWER  = GND
  R64  DDR2_SA_DQS_DN2  BI  = M_C_CPU0_SA_DQS_DN<2>
  R66  VSS1730  POWER  = GND
  R68  VSS1753  POWER  = GND
  R70  DDR1_SA_DQS_DN1  BI  = M_B_CPU0_SA_DQS_DN<1>
  R72  VSS1754  POWER  = GND
  R74  VSS1755  POWER  = GND
  R76  DDR2_SA_DQS_DN0  BI  = M_C_CPU0_SA_DQS_DN<0>
  R78  VSS1756  POWER  = GND
  R80  VCCFA_EHV_FIVRA95  POWER  = PVCCFA_EHV_FIVRA_CPU0
  R82  UPI2_TX_DN6  OUT  = UPI_CPU0_CPU1_P2P2_DN<17>
  R84  VSS1757  POWER  = GND
  R86  PE4_TX_DN2  OUT  = P5E_CPU0_PE4_TX_DN<2>
  R88  VSS1758  POWER  = GND
  R90  PE4_RX_DP2  IN  = P5E_CPU0_PE4_RX_DP<2>
  T2  UPI0_TX_DN3  OUT  = UPI_CPU0_CPU1_P0P1_DN<3>
  T4  VSS1762  POWER  = GND
  T6  UPI0_RX_DP3  IN  = UPI_CPU1_CPU0_P1P0_DN<3>
  T8  VSS1769  POWER  = GND
  T10  PE0_RX_DN3  IN  = P5E_CPU0_PE0_RX_DN<3>
  T12  VSS1739  POWER  = GND
  T14  PE0_TX_DP2  OUT  = P5E_CPU0_PE0_TX_DP<2>
  T16  VSS1740  POWER  = GND
  T18  VSS1741  POWER  = GND
  T20  DDR2_SB_DQ20  BI  = M_C_CPU0_SB_DQ<20>
  T22  DDR2_SB_DQ17  BI  = M_C_CPU0_SB_DQ<17>
  T24  VSS1760  POWER  = GND
  T26  DDR1_SB_DQ4  BI  = M_B_CPU0_SB_DQ<4>
  T28  DDR1_SB_DQ1  BI  = M_B_CPU0_SB_DQ<1>
  T30  VSS1761  POWER  = GND
  T32  DDR2_SB_ECC0  BI  = M_C_CPU0_SB_CB<0>
  T34  DDR2_SB_ECC5  BI  = M_C_CPU0_SB_CB<5>
  T36  VSS1746  POWER  = GND
  T38  DDR2_SB_CS_N0  OUT  = M_C_CPU0_SB_CS_N<0>
  T40  DDR2_SB_CA4  OUT  = M_C_CPU0_SB_CA<4>
  T42  VSS1763  POWER  = GND
  T44  DDR1_SB_CA0  OUT  = M_B_CPU0_SB_CA<0>
  T47  DDR2_SA_PAR  OUT  = M_C_CPU0_SA_PAR
  T49  VSS1749  POWER  = GND
  T51  DDR2_SA_CA2  OUT  = M_C_CPU0_SA_CA<2>
  T53  DDR2_SA_CS_N1  OUT  = M_C_CPU0_SA_CS_N<1>
  T55  VSS1750  POWER  = GND
  T57  DDR1_SA_DQ28  BI  = M_B_CPU0_SA_DQ<28>
  T59  DDR1_SA_DQ25  BI  = M_B_CPU0_SA_DQ<25>
  T61  VSS1764  POWER  = GND
  T63  DDR2_SA_DQ20  BI  = M_C_CPU0_SA_DQ<20>
  T65  DDR2_SA_DQ17  BI  = M_C_CPU0_SA_DQ<17>
  T67  VSS1765  POWER  = GND
  T69  DDR1_SA_DQ12  BI  = M_B_CPU0_SA_DQ<12>
  T71  DDR1_SA_DQ9  BI  = M_B_CPU0_SA_DQ<9>
  T73  VSS1767  POWER  = GND
  T75  DDR2_SA_DQ4  BI  = M_C_CPU0_SA_DQ<4>
  T77  DDR2_SA_DQ1  BI  = M_C_CPU0_SA_DQ<1>
  T79  VSS1768  POWER  = GND
  T81  UPI2_TX_DP5  OUT  = UPI_CPU0_CPU1_P2P2_DP<18>
  T83  VSS1770  POWER  = GND
  T85  VCCFA_EHV_FIVRA96  POWER  = PVCCFA_EHV_FIVRA_CPU0
  T87  PE4_TX_DP2  OUT  = P5E_CPU0_PE4_TX_DP<2>
  T89  VCCFA_EHV_FIVRA97  POWER  = PVCCFA_EHV_FIVRA_CPU0
  T91  PE4_RX_DN2  IN  = P5E_CPU0_PE4_RX_DN<2>
  U1  UPI0_TX_DN4  OUT  = UPI_CPU0_CPU1_P0P1_DN<4>
  U3  VCCFA_EHV9  POWER  = PVCCFA_EHV_CPU0
  U5  UPI0_RX_DN3  IN  = UPI_CPU1_CPU0_P1P0_DP<3>
  U7  VCCFA_EHV_FIVRA100  POWER  = PVCCFA_EHV_FIVRA_CPU0
  U9  PE0_RX_DP3  IN  = P5E_CPU0_PE0_RX_DP<3>
  U11  VCCFA_EHV_FIVRA98  POWER  = PVCCFA_EHV_FIVRA_CPU0
  U13  PE0_TX_DN2  OUT  = P5E_CPU0_PE0_TX_DN<2>
  U15  VCCFA_EHV_FIVRA99  POWER  = PVCCFA_EHV_FIVRA_CPU0
  U17  RSVD164  BI  = NC_CPU0_HBM0_VIEWDIG0
  U19  DDR2_SB_DQ21  BI  = M_C_CPU0_SB_DQ<21>
  U21  DDR2_SB_DQS_DP2  BI  = M_C_CPU0_SB_DQS_DP<2>
  U23  DDR2_SB_DQ16  BI  = M_C_CPU0_SB_DQ<16>
  U25  DDR1_SB_DQ5  BI  = M_B_CPU0_SB_DQ<5>
  U27  DDR1_SB_DQS_DP0  BI  = M_B_CPU0_SB_DQS_DP<0>
  U29  DDR1_SB_DQ0  BI  = M_B_CPU0_SB_DQ<0>
  U31  DDR2_SB_ECC1  BI  = M_C_CPU0_SB_CB<1>
  U33  DDR2_SB_DQS_DP9  BI  = M_C_CPU0_SB_DQS_DP<9>
  U35  DDR2_SB_ECC4  BI  = M_C_CPU0_SB_CB<4>
  U37  DDR2_SB_CS_N1  OUT  = M_C_CPU0_SB_CS_N<1>
  U39  VSS1771  POWER  = GND
  U41  DDR2_SB_CA2  OUT  = M_C_CPU0_SB_CA<2>
  U43  DDR1_SB_CA1  OUT  = M_B_CPU0_SB_CA<1>
  U45  DDR1_CLK_DP0  OUT  = M_B_CPU0_CLK_DP<0>
  U48  DDR2_SA_CA6  OUT  = M_C_CPU0_SA_CA<6>
  U50  DDR2_SA_CA4  OUT  = M_C_CPU0_SA_CA<4>
  U52  VSS1766  POWER  = GND
  U54  DDR2_SA_CS_N0  OUT  = M_C_CPU0_SA_CS_N<0>
  U56  DDR1_SA_DQ29  BI  = M_B_CPU0_SA_DQ<29>
  U58  DDR1_SA_DQS_DP3  BI  = M_B_CPU0_SA_DQS_DP<3>
  U60  DDR1_SA_DQ24  BI  = M_B_CPU0_SA_DQ<24>
  U62  DDR2_SA_DQ21  BI  = M_C_CPU0_SA_DQ<21>
  U64  DDR2_SA_DQS_DP2  BI  = M_C_CPU0_SA_DQS_DP<2>
  U66  DDR2_SA_DQ16  BI  = M_C_CPU0_SA_DQ<16>
  U68  DDR1_SA_DQ13  BI  = M_B_CPU0_SA_DQ<13>
  U70  DDR1_SA_DQS_DP1  BI  = M_B_CPU0_SA_DQS_DP<1>
  U72  DDR1_SA_DQ8  BI  = M_B_CPU0_SA_DQ<8>
  U74  DDR2_SA_DQ5  BI  = M_C_CPU0_SA_DQ<5>
  U76  DDR2_SA_DQS_DP0  BI  = M_C_CPU0_SA_DQS_DP<0>
  U78  DDR2_SA_DQ0  BI  = M_C_CPU0_SA_DQ<0>
  U80  UPI2_TX_DN7  OUT  = UPI_CPU0_CPU1_P2P2_DN<16>
  U82  VSS1772  POWER  = GND
  U84  VSS1773  POWER  = GND
  U86  PE4_TX_DN3  OUT  = P5E_CPU0_PE4_TX_DN<3>
  U88  VSS1774  POWER  = GND
  U90  PE4_RX_DP3  IN  = P5E_CPU0_PE4_RX_DP<3>
  V2  UPI0_TX_DP4  OUT  = UPI_CPU0_CPU1_P0P1_DP<4>
  V4  VSS1788  POWER  = GND
  V6  UPI0_RX_DN4  IN  = UPI_CPU1_CPU0_P1P0_DN<4>
  V8  VSS1812  POWER  = GND
  V10  PE0_RX_DN4  IN  = P5E_CPU0_PE0_RX_DN<4>
  V12  VSS1775  POWER  = GND
  V14  PE0_TX_DN3  OUT  = P5E_CPU0_PE0_TX_DN<3>
  V16  VSS1776  POWER  = GND
  V18  VSS1777  POWER  = GND
  V20  VSS1778  POWER  = GND
  V22  VSS1779  POWER  = GND
  V24  VSS1780  POWER  = GND
  V26  VSS1781  POWER  = GND
  V28  VSS1782  POWER  = GND
  V30  VSS1783  POWER  = GND
  V32  VSS1784  POWER  = GND
  V34  VSS1785  POWER  = GND
  V36  VSS1786  POWER  = GND
  V38  VSS1787  POWER  = GND
  V40  VSS1790  POWER  = GND
  V42  VSS1791  POWER  = GND
  V44  VSS1792  POWER  = GND
